# T6G (Grand Teton) — schematic netlist excerpt (pin names and nets, part order shuffled) for the footprints in the layout excerpt that follows; sources: Cadence DE-HDL packaged netlist, KiCad conversion of 04192023_DAF0TMB3IC0_F0TG_MB_C_brd_V02_OCP.brd

C2332  Q_CAP  22UF 4V 20% X6S  pkg C0402  page 73 : A = PVDDCR_CPU0_P1 ; B = GND
C1837  Q_CAP  0.1UF 25V 10% X7R  pkg 0402  page 137 : A = P3V3_OCP_V3_2 ; B = GND
PC119_4  Q_CAP  22UF 16V 20% X6S  pkg C0805  page 202 : A = SW_P12V_AUX_PVDDCR_CPU1_P0_FLT ; B = GND

(kicad_pcb
	(version 20260206)
	(generator "pcbnew")
	(generator_version "10.0")
	(general
		(thickness 1.6)
		(legacy_teardrops no)
	)
	(paper "A4")
	(title_block
		(title "04192023_DAF0TMB3IC0_F0TG_MB_C_brd_V02_OCP.brd")
		(comment 1 "Grand Teton / footprints 7405-7407 of 8354")
	)
	(layers
		(0 "F.Cu" signal "TOP")
		(4 "In1.Cu" signal "GND")
		(6 "In2.Cu" signal "IN1")
		(8 "In3.Cu" signal "GND1")
		(10 "In4.Cu" signal "IN2")
		(12 "In5.Cu" signal "GND2")
		(14 "In6.Cu" signal "IN3")
		(16 "In7.Cu" signal "GND3")
		(18 "In8.Cu" signal "VCC")
		(20 "In9.Cu" signal "VCC1")
		(22 "In10.Cu" signal "GND4")
		(24 "In11.Cu" signal "IN4")
		(26 "In12.Cu" signal "GND5")
		(28 "In13.Cu" signal "IN5")
		(30 "In14.Cu" signal "GND6")
		(32 "In15.Cu" signal "IN6")
		(34 "In16.Cu" signal "GND7")
		(2 "B.Cu" signal "BOTTOM")
		(9 "F.Adhes" user "F.Adhesive")
		(11 "B.Adhes" user "B.Adhesive")
		(13 "F.Paste" user "Package Geometry/Pastemask Top")
		(15 "B.Paste" user "Package Geometry/Pastemask Bottom")
		(5 "F.SilkS" user "Ref Des/Silkscreen Top")
		(7 "B.SilkS" user "Ref Des/Silkscreen Bottom")
		(1 "F.Mask" user "Board Geometry/Soldermask Top")
		(3 "B.Mask" user "Board Geometry/Soldermask Bottom")
		(17 "Dwgs.User" user "User.Drawings")
		(19 "Cmts.User" user "User.Comments")
		(21 "Eco1.User" user "User.Eco1")
		(23 "Eco2.User" user "User.Eco2")
		(25 "Edge.Cuts" user "Board Geometry/Outline")
		(27 "Margin" user)
		(31 "F.CrtYd" user "Package Geometry/Place Bound Top")
		(29 "B.CrtYd" user "Package Geometry/Place Bound Bottom")
		(35 "F.Fab" user "Ref Des/Assembly Top")
		(33 "B.Fab" user "Ref Des/Assembly Bottom")
	)
	(footprint ""
		(layer "B.Cu")
		(at 111.800386 -249.876564 90)
		(property "Reference" "C2332"
			(at 0 0 90)
			(layer "B.SilkS")
			(hide yes)
			(effects
				(font
					(size 1.27 1.27)
				)
				(justify mirror)
			)
		)
		(property "Value" ""
			(at 0 0 90)
			(layer "B.Fab")
			(effects
				(font
					(size 1.27 1.27)
				)
				(justify mirror)
			)
		)
		(duplicate_pad_numbers_are_jumpers no)
		(fp_line
			(start 0.7874 -0.4064)
			(end -0.7874 -0.4064)
			(stroke
				(width 0.1524)
				(type default)
			)
			(layer "B.SilkS")
		)
		(fp_line
			(start -0.7874 -0.4064)
			(end -0.7874 0.4064)
			(stroke
				(width 0.1524)
				(type default)
			)
			(layer "B.SilkS")
		)
		(fp_line
			(start 0.7874 0.4064)
			(end 0.7874 -0.4064)
			(stroke
				(width 0.1524)
				(type default)
			)
			(layer "B.SilkS")
		)
		(fp_line
			(start -0.7874 0.4064)
			(end 0.7874 0.4064)
			(stroke
				(width 0.1524)
				(type default)
			)
			(layer "B.SilkS")
		)
		(fp_line
			(start 0.67945 -0.305054)
			(end 0.12065 -0.305054)
			(stroke
				(width 0.1)
				(type default)
			)
			(layer "B.Fab")
		)
		(fp_line
			(start 0.12065 -0.305054)
			(end 0.12065 -0.2794)
			(stroke
				(width 0.1)
				(type default)
			)
			(layer "B.Fab")
		)
		(fp_line
			(start -0.12065 -0.3048)
			(end -0.67945 -0.3048)
			(stroke
				(width 0.1)
				(type default)
			)
			(layer "B.Fab")
		)
		(fp_line
			(start -0.67945 -0.3048)
			(end -0.67945 0.3048)
			(stroke
				(width 0.1)
				(type default)
			)
			(layer "B.Fab")
		)
		(fp_line
			(start 0.12065 -0.2794)
			(end -0.12065 -0.2794)
			(stroke
				(width 0.1)
				(type default)
			)
			(layer "B.Fab")
		)
		(fp_line
			(start -0.12065 -0.2794)
			(end -0.12065 -0.3048)
			(stroke
				(width 0.1)
				(type default)
			)
			(layer "B.Fab")
		)
		(fp_line
			(start 0.12065 0.2794)
			(end 0.12065 0.3048)
			(stroke
				(width 0.1)
				(type default)
			)
			(layer "B.Fab")
		)
		(fp_line
			(start -0.120396 0.2794)
			(end 0.12065 0.2794)
			(stroke
				(width 0.1)
				(type default)
			)
			(layer "B.Fab")
		)
		(fp_line
			(start 0.67945 0.3048)
			(end 0.67945 -0.305054)
			(stroke
				(width 0.1)
				(type default)
			)
			(layer "B.Fab")
		)
		(fp_line
			(start 0.12065 0.3048)
			(end 0.67945 0.3048)
			(stroke
				(width 0.1)
				(type default)
			)
			(layer "B.Fab")
		)
		(fp_line
			(start -0.120396 0.3048)
			(end -0.120396 0.2794)
			(stroke
				(width 0.1)
				(type default)
			)
			(layer "B.Fab")
		)
		(fp_line
			(start -0.67945 0.3048)
			(end -0.120396 0.3048)
			(stroke
				(width 0.1)
				(type default)
			)
			(layer "B.Fab")
		)
		(pad "1" smd circle
			(at 0.40005 0 270)
			(size 0 0)
			(layers "B.Cu" "B.Mask" "B.Paste")
			(net "PVDDCR_CPU0_P1")
		)
		(pad "2" smd circle
			(at -0.40005 0 270)
			(size 0 0)
			(layers "B.Cu" "B.Mask" "B.Paste")
			(net "GND")
		)
	)
	(footprint ""
		(layer "B.Cu")
		(at 62.53988 -8.981948 90)
		(property "Reference" "C1837"
			(at 0 0 90)
			(layer "B.SilkS")
			(hide yes)
			(effects
				(font
					(size 1.27 1.27)
				)
				(justify mirror)
			)
		)
		(property "Value" ""
			(at 0 0 90)
			(layer "B.Fab")
			(effects
				(font
					(size 1.27 1.27)
				)
				(justify mirror)
			)
		)
		(duplicate_pad_numbers_are_jumpers no)
		(fp_line
			(start 0.7874 -0.4064)
			(end -0.7874 -0.4064)
			(stroke
				(width 0.1524)
				(type default)
			)
			(layer "B.SilkS")
		)
		(fp_line
			(start -0.7874 -0.4064)
			(end -0.7874 0.4064)
			(stroke
				(width 0.1524)
				(type default)
			)
			(layer "B.SilkS")
		)
		(fp_line
			(start 0.7874 0.4064)
			(end 0.7874 -0.4064)
			(stroke
				(width 0.1524)
				(type default)
			)
			(layer "B.SilkS")
		)
		(fp_line
			(start -0.7874 0.4064)
			(end 0.7874 0.4064)
			(stroke
				(width 0.1524)
				(type default)
			)
			(layer "B.SilkS")
		)
		(fp_line
			(start 0.67945 -0.305054)
			(end 0.12065 -0.305054)
			(stroke
				(width 0.1)
				(type default)
			)
			(layer "B.Fab")
		)
		(fp_line
			(start 0.12065 -0.305054)
			(end 0.12065 -0.2794)
			(stroke
				(width 0.1)
				(type default)
			)
			(layer "B.Fab")
		)
		(fp_line
			(start -0.12065 -0.3048)
			(end -0.67945 -0.3048)
			(stroke
				(width 0.1)
				(type default)
			)
			(layer "B.Fab")
		)
		(fp_line
			(start -0.67945 -0.3048)
			(end -0.67945 0.3048)
			(stroke
				(width 0.1)
				(type default)
			)
			(layer "B.Fab")
		)
		(fp_line
			(start 0.12065 -0.2794)
			(end -0.12065 -0.2794)
			(stroke
				(width 0.1)
				(type default)
			)
			(layer "B.Fab")
		)
		(fp_line
			(start -0.12065 -0.2794)
			(end -0.12065 -0.3048)
			(stroke
				(width 0.1)
				(type default)
			)
			(layer "B.Fab")
		)
		(fp_line
			(start 0.12065 0.2794)
			(end 0.12065 0.3048)
			(stroke
				(width 0.1)
				(type default)
			)
			(layer "B.Fab")
		)
		(fp_line
			(start -0.120396 0.2794)
			(end 0.12065 0.2794)
			(stroke
				(width 0.1)
				(type default)
			)
			(layer "B.Fab")
		)
		(fp_line
			(start 0.67945 0.3048)
			(end 0.67945 -0.305054)
			(stroke
				(width 0.1)
				(type default)
			)
			(layer "B.Fab")
		)
		(fp_line
			(start 0.12065 0.3048)
			(end 0.67945 0.3048)
			(stroke
				(width 0.1)
				(type default)
			)
			(layer "B.Fab")
		)
		(fp_line
			(start -0.120396 0.3048)
			(end -0.120396 0.2794)
			(stroke
				(width 0.1)
				(type default)
			)
			(layer "B.Fab")
		)
		(fp_line
			(start -0.67945 0.3048)
			(end -0.120396 0.3048)
			(stroke
				(width 0.1)
				(type default)
			)
			(layer "B.Fab")
		)
		(pad "1" smd circle
			(at 0.40005 0 270)
			(size 0 0)
			(layers "B.Cu" "B.Mask" "B.Paste")
			(net "P3V3_OCP_V3_2")
		)
		(pad "2" smd circle
			(at -0.40005 0 270)
			(size 0 0)
			(layers "B.Cu" "B.Mask" "B.Paste")
			(net "GND")
		)
	)
	(footprint ""
		(layer "B.Cu")
		(at 311.945782 -346.784168 90)
		(property "Reference" "PC119_4"
			(at 0 0 90)
			(layer "B.SilkS")
			(hide yes)
			(effects
				(font
					(size 1.27 1.27)
				)
				(justify mirror)
			)
		)
		(property "Value" ""
			(at 0 0 90)
			(layer "B.Fab")
			(effects
				(font
					(size 1.27 1.27)
				)
				(justify mirror)
			)
		)
		(duplicate_pad_numbers_are_jumpers no)
		(fp_line
			(start 1.524 -0.762)
			(end -1.524 -0.762)
			(stroke
				(width 0.1524)
				(type default)
			)
			(layer "B.SilkS")
		)
		(fp_line
			(start -1.524 -0.762)
			(end -1.524 0.762)
			(stroke
				(width 0.1524)
				(type default)
			)
			(layer "B.SilkS")
		)
		(fp_line
			(start 1.524 0.762)
			(end 1.524 -0.762)
			(stroke
				(width 0.1524)
				(type default)
			)
			(layer "B.SilkS")
		)
		(fp_line
			(start -1.524 0.762)
			(end 1.524 0.762)
			(stroke
				(width 0.1524)
				(type default)
			)
			(layer "B.SilkS")
		)
		(fp_line
			(start 1.1049 -0.724916)
			(end 1.1049 0.724916)
			(stroke
				(width 0.1)
				(type default)
			)
			(layer "B.Fab")
		)
		(fp_line
			(start -1.1049 -0.724916)
			(end 1.1049 -0.724916)
			(stroke
				(width 0.1)
				(type default)
			)
			(layer "B.Fab")
		)
		(fp_line
			(start 1.1049 0.724916)
			(end -1.1049 0.724916)
			(stroke
				(width 0.1)
				(type default)
			)
			(layer "B.Fab")
		)
		(fp_line
			(start -1.1049 0.724916)
			(end -1.1049 -0.724916)
			(stroke
				(width 0.1)
				(type default)
			)
			(layer "B.Fab")
		)
		(pad "1" smd rect
			(at 0.889 0 90)
			(size 1.016 1.27)
			(layers "B.Cu" "B.Mask" "B.Paste")
			(net "SW_P12V_AUX_PVDDCR_CPU1_P0_FLT")
		)
		(pad "2" smd rect
			(at -0.889 0 90)
			(size 1.016 1.27)
			(layers "B.Cu" "B.Mask" "B.Paste")
			(net "GND")
		)
	)
)
